(kicad_pcb
	(version 20241229)
	(generator "pcbnew")
	(generator_version "9.0")
	(general
		(thickness 1.711)
		(legacy_teardrops no)
	)
	(paper "A4")
	(title_block
		(title "Antmicro Baseboard for Jetson AGX Thor")
		(date "2026-02-18")
		(rev "1.1.0")
		(company "Antmicro Ltd")
		(comment 1 "www.antmicro.com")
		(comment 9 "footprint 110 of 1170 (J1), pads 565-644 of 699")
	)
	(layers
		(0 "F.Cu" signal)
		(4 "In1.Cu" signal)
		(6 "In2.Cu" signal)
		(8 "In3.Cu" signal)
		(10 "In4.Cu" jumper)
		(12 "In5.Cu" signal)
		(14 "In6.Cu" signal)
		(16 "In7.Cu" signal)
		(18 "In8.Cu" signal)
		(2 "B.Cu" signal)
		(9 "F.Adhes" user "F.Adhesive")
		(11 "B.Adhes" user "B.Adhesive")
		(13 "F.Paste" user)
		(15 "B.Paste" user)
		(5 "F.SilkS" user "F.Silkscreen")
		(7 "B.SilkS" user "B.Silkscreen")
		(1 "F.Mask" user)
		(3 "B.Mask" user)
		(17 "Dwgs.User" user "User.Drawings")
		(19 "Cmts.User" user "User.Comments")
		(21 "Eco1.User" user "User.Eco1")
		(23 "Eco2.User" user "User.Eco2")
		(25 "Edge.Cuts" user)
		(27 "Margin" user)
		(31 "F.CrtYd" user "F.Courtyard")
		(29 "B.CrtYd" user "B.Courtyard")
		(35 "F.Fab" user)
		(33 "B.Fab" user)
	)
	(footprint "antmicro-footprints:Conn_Hermaphroditic_Molex_203456-0003_mirrored"
		(locked yes)
		(layer "F.Cu")
		(at 116.530532 78.15)
		(descr "Mirrored version of: https://www.molex.com/content/dam/molex/molex-dot-com/products/automated/en-us/salesdrawingpdf/203/203456/2034560003_sd.pdf")
		(property "Reference" "J1"
			(at -32.25 -11.2 180)
			(layer "F.SilkS")
			(effects
				(font
					(size 0.7 0.7)
					(thickness 0.15)
				)
				(justify right top)
			)
		)
		(property "Value" "Hermaphroditic_Molex_203456-0003_CUSTOM_Jetson_AGX_Thor_H8mm"
			(at 0.1 12.9 0)
			(layer "F.Fab")
			(effects
				(font
					(size 0.7 0.7)
					(thickness 0.15)
				)
				(justify right top)
			)
		)
		(property "Datasheet" "https://www.molex.com/content/dam/molex/molex-dot-com/products/automated/en-us/salesdrawingpdf/203/203456/2034560003_sd.pdf?inline"
			(at 0.1 0.2 0)
			(layer "F.Fab")
			(hide yes)
			(effects
				(font
					(size 0.7 0.7)
					(thickness 0.15)
				)
				(justify right top)
			)
		)
		(property "Description" "Mirror Mezz Hermaphroditic Connector, 5.50mm Connector Height, BGA-Attach Mounting, 7 Pair, 11 Row, 699 Circuits, 0.76µm Gold Plating, without Pegs"
			(at 0.1 0.2 0)
			(layer "F.Fab")
			(hide yes)
			(effects
				(font
					(size 0.7 0.7)
					(thickness 0.15)
				)
				(justify right top)
			)
		)
		(property "MPN" "203456-0003"
			(at 0 0 0)
			(unlocked yes)
			(layer "F.Fab")
			(hide yes)
			(effects
				(font
					(size 1 1)
					(thickness 0.15)
				)
			)
		)
		(property "Manufacturer" "Molex"
			(at 0 0 0)
			(unlocked yes)
			(layer "F.Fab")
			(hide yes)
			(effects
				(font
					(size 1 1)
					(thickness 0.15)
				)
			)
		)
		(property "Author" "Antmicro"
			(at 0 0 0)
			(unlocked yes)
			(layer "F.Fab")
			(hide yes)
			(effects
				(font
					(size 1 1)
					(thickness 0.15)
				)
			)
		)
		(property "License" "Apache-2.0"
			(at 0 0 0)
			(unlocked yes)
			(layer "F.Fab")
			(hide yes)
			(effects
				(font
					(size 1 1)
					(thickness 0.15)
				)
			)
		)
		(sheetname "/SoM_IO/")
		(sheetfile "som_io.kicad_sch")
		(solder_mask_margin 0.05)
		(attr smd)
		(pad "J53" smd circle
			(at 19.4 -4.5 90)
			(size 0.5 0.5)
			(layers "F.Cu" "F.Mask" "F.Paste")
			(net 331 "/SoM_IO/I2C0_SDA_1V8")
			(pinfunction "I2C0_DAT")
			(pintype "bidirectional")
		)
		(pad "J54" smd circle
			(at 20.3 -4.5 90)
			(size 0.5 0.5)
			(layers "F.Cu" "F.Mask" "F.Paste")
			(net 416 "/Expansion connector/GPIO.MCLK02")
			(pinfunction "MCLK02")
			(pintype "bidirectional")
		)
		(pad "J55" smd circle
			(at 21.2 -4.5 90)
			(size 0.5 0.5)
			(layers "F.Cu" "F.Mask" "F.Paste")
			(net 624 "unconnected-(J1D-I2C9_DAT-PadJ55)")
			(pinfunction "I2C9_DAT")
			(pintype "bidirectional+no_connect")
		)
		(pad "J56" smd circle
			(at 22.1 -4.5 90)
			(size 0.5 0.5)
			(layers "F.Cu" "F.Mask" "F.Paste")
			(net 1 "GND")
			(pinfunction "GND")
			(pintype "passive")
		)
		(pad "J57" smd circle
			(at 23 -4.5 90)
			(size 0.5 0.5)
			(layers "F.Cu" "F.Mask" "F.Paste")
			(net 421 "/Expansion connector/SPI1.SCK")
			(pinfunction "SPI1_CLK")
			(pintype "bidirectional")
		)
		(pad "J58" smd circle
			(at 23.9 -4.5 90)
			(size 0.5 0.5)
			(layers "F.Cu" "F.Mask" "F.Paste")
			(net 118 "/Expansion connector/UART5.TX")
			(pinfunction "UART5_TX")
			(pintype "output")
		)
		(pad "J59" smd circle
			(at 24.8 -4.5 90)
			(size 0.5 0.5)
			(layers "F.Cu" "F.Mask" "F.Paste")
			(net 551 "unconnected-(J1H-I2S3_DIN-PadJ59)")
			(pinfunction "I2S3_DIN")
			(pintype "input+no_connect")
		)
		(pad "J60" smd circle
			(at 25.7 -4.5 90)
			(size 0.5 0.5)
			(layers "F.Cu" "F.Mask" "F.Paste")
			(net 609 "/SoM_Power/~{MOD_SLEEP}")
			(pinfunction "MODULE_SLEEP_N")
			(pintype "output")
		)
		(pad "J61" smd circle
			(at 26.6 -4.5 90)
			(size 0.5 0.5)
			(layers "F.Cu" "F.Mask" "F.Paste")
			(net 139 "/SoM_IO/I2C2_SCL_1V8")
			(pinfunction "I2C2_CLK")
			(pintype "bidirectional")
		)
		(pad "J62" smd circle
			(at 27.5 -4.5 90)
			(size 0.5 0.5)
			(layers "F.Cu" "F.Mask" "F.Paste")
			(net 1 "GND")
			(pinfunction "GND")
			(pintype "passive")
		)
		(pad "J63" smd circle
			(at 28.4 -4.5 90)
			(size 0.5 0.5)
			(layers "F.Cu" "F.Mask" "F.Paste")
			(net 12 "SYS_VIN_HV")
			(pinfunction "SYS_VIN_HV")
			(pintype "passive")
		)
		(pad "J64" smd circle
			(at 29.3 -4.5 90)
			(size 0.5 0.5)
			(layers "F.Cu" "F.Mask" "F.Paste")
			(net 12 "SYS_VIN_HV")
			(pinfunction "SYS_VIN_HV")
			(pintype "passive")
		)
		(pad "J65" smd circle
			(at 30.2 -4.5 90)
			(size 0.5 0.5)
			(layers "F.Cu" "F.Mask" "F.Paste")
			(net 12 "SYS_VIN_HV")
			(pinfunction "SYS_VIN_HV")
			(pintype "passive")
		)
		(pad "K3" smd circle
			(at -28.2 -6 90)
			(size 0.5 0.5)
			(layers "F.Cu" "F.Mask" "F.Paste")
			(net 12 "SYS_VIN_HV")
			(pinfunction "SYS_VIN_HV")
			(pintype "passive")
		)
		(pad "K4" smd circle
			(at -27.3 -6 90)
			(size 0.5 0.5)
			(layers "F.Cu" "F.Mask" "F.Paste")
			(net 1 "GND")
			(pinfunction "GND")
			(pintype "passive")
		)
		(pad "K5" smd circle
			(at -26.4 -6 90)
			(size 0.5 0.5)
			(layers "F.Cu" "F.Mask" "F.Paste")
			(net 48 "/SoM_IO/I2C1_SCL_1V8")
			(pinfunction "I2C1_CLK")
			(pintype "bidirectional")
		)
		(pad "K6" smd circle
			(at -25.5 -6 90)
			(size 0.5 0.5)
			(layers "F.Cu" "F.Mask" "F.Paste")
			(net 368 "/Expansion connector/GPIO.21")
			(pinfunction "GPIO60")
			(pintype "passive")
		)
		(pad "K7" smd circle
			(at -24.6 -6 90)
			(size 0.5 0.5)
			(layers "F.Cu" "F.Mask" "F.Paste")
			(net 629 "unconnected-(J1G-FSI_GPIO27-PadK7)")
			(pinfunction "FSI_GPIO27")
			(pintype "passive+no_connect")
		)
		(pad "K8" smd circle
			(at -23.7 -6 90)
			(size 0.5 0.5)
			(layers "F.Cu" "F.Mask" "F.Paste")
			(net 1 "GND")
			(pinfunction "GND")
			(pintype "passive")
		)
		(pad "K9" smd circle
			(at -22.8 -6 90)
			(size 0.5 0.5)
			(layers "F.Cu" "F.Mask" "F.Paste")
			(net 632 "unconnected-(J1G-FSI_GPIO22-PadK9)")
			(pinfunction "FSI_GPIO22")
			(pintype "passive+no_connect")
		)
		(pad "K10" smd circle
			(at -21.9 -6 90)
			(size 0.5 0.5)
			(layers "F.Cu" "F.Mask" "F.Paste")
			(net 320 "unconnected-(J1D-FSI_GPIO28-PadK10)")
			(pinfunction "FSI_GPIO28")
			(pintype "passive+no_connect")
		)
		(pad "K11" smd circle
			(at -21 -6 90)
			(size 0.5 0.5)
			(layers "F.Cu" "F.Mask" "F.Paste")
			(net 1 "GND")
			(pinfunction "GND")
			(pintype "passive")
		)
		(pad "K12" smd circle
			(at -20.1 -6 90)
			(size 0.5 0.5)
			(layers "F.Cu" "F.Mask" "F.Paste")
			(net 517 "/Expansion connector/PCIe_{C3x2}.TX0-")
			(pinfunction "UPHY_TX6_N")
			(pintype "output")
		)
		(pad "K13" smd circle
			(at -19.2 -6 90)
			(size 0.5 0.5)
			(layers "F.Cu" "F.Mask" "F.Paste")
			(net 459 "/Expansion connector/PCIe_{C3x2}.TX0+")
			(pinfunction "UPHY_TX6_P")
			(pintype "output")
		)
		(pad "K14" smd circle
			(at -18.3 -6 90)
			(size 0.5 0.5)
			(layers "F.Cu" "F.Mask" "F.Paste")
			(net 1 "GND")
			(pinfunction "GND")
			(pintype "passive")
		)
		(pad "K15" smd circle
			(at -17 -6 90)
			(size 0.5 0.5)
			(layers "F.Cu" "F.Mask" "F.Paste")
			(net 1 "GND")
			(pinfunction "GND")
			(pintype "passive")
		)
		(pad "K16" smd circle
			(at -16.1 -6 90)
			(size 0.5 0.5)
			(layers "F.Cu" "F.Mask" "F.Paste")
			(net 586 "unconnected-(J1B-UPHY_TX16_N-PadK16)")
			(pinfunction "UPHY_TX16_N")
			(pintype "output+no_connect")
		)
		(pad "K17" smd circle
			(at -15.2 -6 90)
			(size 0.5 0.5)
			(layers "F.Cu" "F.Mask" "F.Paste")
			(net 754 "unconnected-(J1B-UPHY_TX16_P-PadK17)")
			(pinfunction "UPHY_TX16_P")
			(pintype "output+no_connect")
		)
		(pad "K18" smd circle
			(at -14.3 -6 90)
			(size 0.5 0.5)
			(layers "F.Cu" "F.Mask" "F.Paste")
			(net 1 "GND")
			(pinfunction "GND")
			(pintype "passive")
		)
		(pad "K19" smd circle
			(at -13 -6 90)
			(size 0.5 0.5)
			(layers "F.Cu" "F.Mask" "F.Paste")
			(net 1 "GND")
			(pinfunction "GND")
			(pintype "passive")
		)
		(pad "K20" smd circle
			(at -12.1 -6 90)
			(size 0.5 0.5)
			(layers "F.Cu" "F.Mask" "F.Paste")
			(net 516 "/Expansion connector/PCIe_{C2x1}.TX0-")
			(pinfunction "UPHY_TX4_N")
			(pintype "output")
		)
		(pad "K21" smd circle
			(at -11.2 -6 90)
			(size 0.5 0.5)
			(layers "F.Cu" "F.Mask" "F.Paste")
			(net 478 "/Expansion connector/PCIe_{C2x1}.TX0+")
			(pinfunction "UPHY_TX4_P")
			(pintype "output")
		)
		(pad "K22" smd circle
			(at -10.3 -6 90)
			(size 0.5 0.5)
			(layers "F.Cu" "F.Mask" "F.Paste")
			(net 1 "GND")
			(pinfunction "GND")
			(pintype "passive")
		)
		(pad "K23" smd circle
			(at -9 -6 90)
			(size 0.5 0.5)
			(layers "F.Cu" "F.Mask" "F.Paste")
			(net 1 "GND")
			(pinfunction "GND")
			(pintype "passive")
		)
		(pad "K24" smd circle
			(at -8.1 -6 90)
			(size 0.5 0.5)
			(layers "F.Cu" "F.Mask" "F.Paste")
			(net 418 "/M.2/PCIe_{C5x4}.TX1-")
			(pinfunction "UPHY_TX9_N")
			(pintype "output")
		)
		(pad "K25" smd circle
			(at -7.2 -6 90)
			(size 0.5 0.5)
			(layers "F.Cu" "F.Mask" "F.Paste")
			(net 392 "/M.2/PCIe_{C5x4}.TX1+")
			(pinfunction "UPHY_TX9_P")
			(pintype "output")
		)
		(pad "K26" smd circle
			(at -6.3 -6 90)
			(size 0.5 0.5)
			(layers "F.Cu" "F.Mask" "F.Paste")
			(net 1 "GND")
			(pinfunction "GND")
			(pintype "passive")
		)
		(pad "K27" smd circle
			(at -5 -6 90)
			(size 0.5 0.5)
			(layers "F.Cu" "F.Mask" "F.Paste")
			(net 1 "GND")
			(pinfunction "GND")
			(pintype "passive")
		)
		(pad "K28" smd circle
			(at -4.1 -6 90)
			(size 0.5 0.5)
			(layers "F.Cu" "F.Mask" "F.Paste")
			(net 696 "unconnected-(J1B-UPHY_TX13_N-PadK28)")
			(pinfunction "UPHY_TX13_N")
			(pintype "output+no_connect")
		)
		(pad "K29" smd circle
			(at -3.2 -6 90)
			(size 0.5 0.5)
			(layers "F.Cu" "F.Mask" "F.Paste")
			(net 602 "unconnected-(J1B-UPHY_TX13_P-PadK29)")
			(pinfunction "UPHY_TX13_P")
			(pintype "output+no_connect")
		)
		(pad "K30" smd circle
			(at -2.3 -6 90)
			(size 0.5 0.5)
			(layers "F.Cu" "F.Mask" "F.Paste")
			(net 1 "GND")
			(pinfunction "GND")
			(pintype "passive")
		)
		(pad "K31" smd circle
			(at -1 -6 90)
			(size 0.5 0.5)
			(layers "F.Cu" "F.Mask" "F.Paste")
			(net 1 "GND")
			(pinfunction "GND")
			(pintype "passive")
		)
		(pad "K32" smd circle
			(at -0.1 -6 90)
			(size 0.5 0.5)
			(layers "F.Cu" "F.Mask" "F.Paste")
			(net 618 "/Recovery USB/USBSS0.TX+")
			(pinfunction "UPHY_TX0_P")
			(pintype "output")
		)
		(pad "K33" smd circle
			(at 0.8 -6 90)
			(size 0.5 0.5)
			(layers "F.Cu" "F.Mask" "F.Paste")
			(net 630 "/Recovery USB/USBSS0.TX-")
			(pinfunction "UPHY_TX0_N")
			(pintype "output")
		)
		(pad "K34" smd circle
			(at 1.7 -6 90)
			(size 0.5 0.5)
			(layers "F.Cu" "F.Mask" "F.Paste")
			(net 1 "GND")
			(pinfunction "GND")
			(pintype "passive")
		)
		(pad "K35" smd circle
			(at 3 -6 90)
			(size 0.5 0.5)
			(layers "F.Cu" "F.Mask" "F.Paste")
			(net 1 "GND")
			(pinfunction "GND")
			(pintype "passive")
		)
		(pad "K36" smd circle
			(at 3.9 -6 90)
			(size 0.5 0.5)
			(layers "F.Cu" "F.Mask" "F.Paste")
			(net 769 "unconnected-(J1G-FSI_GPIO04-PadK36)")
			(pinfunction "FSI_GPIO04")
			(pintype "passive+no_connect")
		)
		(pad "K37" smd circle
			(at 4.8 -6 90)
			(size 0.5 0.5)
			(layers "F.Cu" "F.Mask" "F.Paste")
			(net 875 "Net-(J1A-FSI_GPIO03)")
			(pinfunction "FSI_GPIO03")
			(pintype "passive")
		)
		(pad "K38" smd circle
			(at 5.7 -6 90)
			(size 0.5 0.5)
			(layers "F.Cu" "F.Mask" "F.Paste")
			(net 1 "GND")
			(pinfunction "GND")
			(pintype "passive")
		)
		(pad "K39" smd circle
			(at 7 -6 90)
			(size 0.5 0.5)
			(layers "F.Cu" "F.Mask" "F.Paste")
			(net 1 "GND")
			(pinfunction "GND")
			(pintype "passive")
		)
		(pad "K40" smd circle
			(at 7.9 -6 90)
			(size 0.5 0.5)
			(layers "F.Cu" "F.Mask" "F.Paste")
			(net 119 "unconnected-(J1A-MID0-PadK40)")
			(pinfunction "MID0")
			(pintype "passive+no_connect")
		)
		(pad "K41" smd circle
			(at 8.8 -6 90)
			(size 0.5 0.5)
			(layers "F.Cu" "F.Mask" "F.Paste")
			(net 1 "GND")
			(pinfunction "GND")
			(pintype "passive")
		)
		(pad "K42" smd circle
			(at 9.7 -6 90)
			(size 0.5 0.5)
			(layers "F.Cu" "F.Mask" "F.Paste")
			(net 1 "GND")
			(pinfunction "GND")
			(pintype "passive")
		)
		(pad "K43" smd circle
			(at 10.6 -6 90)
			(size 0.5 0.5)
			(layers "F.Cu" "F.Mask" "F.Paste")
			(net 135 "/CSI/CAM3.CSI6_D0-")
			(pinfunction "CSI6_D0_N")
			(pintype "input")
		)
		(pad "K44" smd circle
			(at 11.5 -6 90)
			(size 0.5 0.5)
			(layers "F.Cu" "F.Mask" "F.Paste")
			(net 152 "/CSI/CAM3.CSI6_D0+")
			(pinfunction "CSI6_D0_P")
			(pintype "input")
		)
		(pad "K45" smd circle
			(at 12.4 -6 90)
			(size 0.5 0.5)
			(layers "F.Cu" "F.Mask" "F.Paste")
			(net 1 "GND")
			(pinfunction "GND")
			(pintype "passive")
		)
		(pad "K46" smd circle
			(at 13.3 -6 90)
			(size 0.5 0.5)
			(layers "F.Cu" "F.Mask" "F.Paste")
			(net 1247 "/SoM_IO2/DP1.TX3_C+")
			(pinfunction "DP1_D3_HDMI_CK_P")
			(pintype "output")
		)
		(pad "K47" smd circle
			(at 14.2 -6 90)
			(size 0.5 0.5)
			(layers "F.Cu" "F.Mask" "F.Paste")
			(net 1251 "/SoM_IO2/DP1.TX3_C-")
			(pinfunction "DP1_D3_HDMI_CK_N")
			(pintype "output")
		)
		(pad "K48" smd circle
			(at 15.1 -6 90)
			(size 0.5 0.5)
			(layers "F.Cu" "F.Mask" "F.Paste")
			(net 1 "GND")
			(pinfunction "GND")
			(pintype "passive")
		)
		(pad "K49" smd circle
			(at 16 -6 90)
			(size 0.5 0.5)
			(layers "F.Cu" "F.Mask" "F.Paste")
			(net 874 "unconnected-(J1C-GPIO25-PadK49)")
			(pinfunction "GPIO25")
			(pintype "passive+no_connect")
		)
		(pad "K50" smd circle
			(at 16.9 -6 90)
			(size 0.5 0.5)
			(layers "F.Cu" "F.Mask" "F.Paste")
			(net 788 "/SoM_IO2/DP0.HPD")
			(pinfunction "HPD0")
			(pintype "bidirectional")
		)
		(pad "K51" smd circle
			(at 17.8 -6 90)
			(size 0.5 0.5)
			(layers "F.Cu" "F.Mask" "F.Paste")
			(net 660 "unconnected-(J1I-GPIO69-PadK51)")
			(pinfunction "GPIO69")
			(pintype "passive+no_connect")
		)
		(pad "K52" smd circle
			(at 18.7 -6 90)
			(size 0.5 0.5)
			(layers "F.Cu" "F.Mask" "F.Paste")
			(net 876 "unconnected-(J1I-GPIO70-PadK52)")
			(pinfunction "GPIO70")
			(pintype "passive+no_connect")
		)
		(pad "K53" smd circle
			(at 19.6 -6 90)
			(size 0.5 0.5)
			(layers "F.Cu" "F.Mask" "F.Paste")
			(net 138 "/SoM_IO/UART1.TX")
			(pinfunction "UART1_TX")
			(pintype "output")
		)
		(pad "K54" smd circle
			(at 20.5 -6 90)
			(size 0.5 0.5)
			(layers "F.Cu" "F.Mask" "F.Paste")
			(net 108 "/SoM_IO/UART1.RX")
			(pinfunction "UART1_RX")
			(pintype "input")
		)
		(pad "K55" smd circle
			(at 21.4 -6 90)
			(size 0.5 0.5)
			(layers "F.Cu" "F.Mask" "F.Paste")
			(net 1 "GND")
			(pinfunction "GND")
			(pintype "passive")
		)
		(pad "K56" smd circle
			(at 22.3 -6 90)
			(size 0.5 0.5)
			(layers "F.Cu" "F.Mask" "F.Paste")
			(net 748 "unconnected-(J1I-GPIO19-PadK56)")
			(pinfunction "GPIO19")
			(pintype "output+no_connect")
		)
		(pad "K57" smd circle
			(at 23.2 -6 90)
			(size 0.5 0.5)
			(layers "F.Cu" "F.Mask" "F.Paste")
			(net 787 "unconnected-(J1I-PWM01-PadK57)")
			(pinfunction "PWM01")
			(pintype "passive+no_connect")
		)
		(pad "K58" smd circle
			(at 24.1 -6 90)
			(size 0.5 0.5)
			(layers "F.Cu" "F.Mask" "F.Paste")
			(net 56 "/Expansion connector/UART5.RTS")
			(pinfunction "UART5_RTS")
			(pintype "output")
		)
		(pad "K59" smd circle
			(at 25 -6 90)
			(size 0.5 0.5)
			(layers "F.Cu" "F.Mask" "F.Paste")
			(net 587 "unconnected-(J1H-I2S3_DOUT-PadK59)")
			(pinfunction "I2S3_DOUT")
			(pintype "output+no_connect")
		)
		(pad "K60" smd circle
			(at 25.9 -6 90)
			(size 0.5 0.5)
			(layers "F.Cu" "F.Mask" "F.Paste")
			(net 494 "/SoM_IO/UART3_DEBUG_RX_1V8")
			(pinfunction "UART3_RX_DEBUG")
			(pintype "input")
		)
		(pad "K61" smd circle
			(at 26.8 -6 90)
			(size 0.5 0.5)
			(layers "F.Cu" "F.Mask" "F.Paste")
			(net 167 "/SoM_IO/I2C2_SDA_1V8")
			(pinfunction "I2C2_DAT")
			(pintype "bidirectional")
		)
		(pad "K62" smd circle
			(at 27.7 -6 90)
			(size 0.5 0.5)
			(layers "F.Cu" "F.Mask" "F.Paste")
			(net 97 "/Peripherals/FAN_PWM")
			(pinfunction "FAN_PWM")
			(pintype "output")
		)
		(pad "K63" smd circle
			(at 28.6 -6 90)
			(size 0.5 0.5)
			(layers "F.Cu" "F.Mask" "F.Paste")
			(net 1 "GND")
			(pinfunction "GND")
			(pintype "passive")
		)
		(pad "L3" smd circle
			(at -28.4 -7.5 90)
			(size 0.5 0.5)
			(layers "F.Cu" "F.Mask" "F.Paste")
			(net 1 "GND")
			(pinfunction "GND")
			(pintype "passive")
		)
		(pad "L4" smd circle
			(at -27.5 -7.5 90)
			(size 0.5 0.5)
			(layers "F.Cu" "F.Mask" "F.Paste")
			(net 757 "unconnected-(J1I-UART4_RTS-PadL4)")
			(pinfunction "UART4_RTS")
			(pintype "output+no_connect")
		)
		(pad "L5" smd circle
			(at -26.6 -7.5 90)
			(size 0.5 0.5)
			(layers "F.Cu" "F.Mask" "F.Paste")
			(net 616 "unconnected-(J1I-UART4_TX-PadL5)")
			(pinfunction "UART4_TX")
			(pintype "output+no_connect")
		)
		(pad "L6" smd circle
			(at -25.7 -7.5 90)
			(size 0.5 0.5)
			(layers "F.Cu" "F.Mask" "F.Paste")
			(net 765 "unconnected-(J1I-UART4_CTS-PadL6)")
			(pinfunction "UART4_CTS")
			(pintype "input+no_connect")
		)
		(pad "L7" smd circle
			(at -24.8 -7.5 90)
			(size 0.5 0.5)
			(layers "F.Cu" "F.Mask" "F.Paste")
			(net 1 "GND")
			(pinfunction "GND")
			(pintype "passive")
		)
		(pad "L8" smd circle
			(at -23.9 -7.5 90)
			(size 0.5 0.5)
			(layers "F.Cu" "F.Mask" "F.Paste")
			(net 96 "/SoM_IO/I2C1_SDA_1V8")
			(pinfunction "I2C1_DAT")
			(pintype "bidirectional")
		)
	)
)
